(kicad_pcb
	(version 20241229)
	(generator "pcbnew")
	(generator_version "9.0")
	(general
		(thickness 1.6642)
		(legacy_teardrops no)
	)
	(paper "A3")
	(title_block
		(title "PolarFire SoM")
		(date "2025-07-22")
		(rev "1.1.4")
		(company "Antmicro Ltd")
		(comment 1 "www.antmicro.com")
		(comment 9 "footprints 9-12 of 470")
	)
	(layers
		(0 "F.Cu" mixed)
		(4 "In1.Cu" power)
		(6 "In2.Cu" signal)
		(8 "In3.Cu" power)
		(10 "In4.Cu" signal)
		(12 "In5.Cu" power)
		(14 "In6.Cu" power)
		(16 "In7.Cu" signal)
		(18 "In8.Cu" power)
		(20 "In9.Cu" signal)
		(22 "In10.Cu" power)
		(24 "In11.Cu" signal)
		(26 "In12.Cu" signal)
		(2 "B.Cu" mixed)
		(9 "F.Adhes" user "F.Adhesive")
		(11 "B.Adhes" user "B.Adhesive")
		(13 "F.Paste" user)
		(15 "B.Paste" user)
		(5 "F.SilkS" user "F.Silkscreen")
		(7 "B.SilkS" user "B.Silkscreen")
		(1 "F.Mask" user)
		(3 "B.Mask" user)
		(17 "Dwgs.User" user "User.Drawings")
		(19 "Cmts.User" user "User.Comments")
		(21 "Eco1.User" user "User.Eco1")
		(23 "Eco2.User" user "User.Eco2")
		(25 "Edge.Cuts" user)
		(27 "Margin" user)
		(31 "F.CrtYd" user "F.Courtyard")
		(29 "B.CrtYd" user "B.Courtyard")
		(35 "F.Fab" user)
		(33 "B.Fab" user)
	)
	(footprint "antmicro-footprints:R_Array_4x0201_Panasonic_EXB18V"
		(layer "F.Cu")
		(at 196.225 121.25 -90)
		(property "Reference" "R27"
			(at 1.75 1.185 180)
			(layer "F.SilkS")
			(effects
				(font
					(size 0.7 0.7)
					(thickness 0.15)
				)
				(justify left bottom)
			)
		)
		(property "Value" "R_4x0R_0201_array"
			(at -1.1 1.8 90)
			(layer "F.Fab")
			(hide yes)
			(effects
				(font
					(size 0.7 0.7)
					(thickness 0.15)
				)
				(justify right bottom)
			)
		)
		(property "Datasheet" "http://industrial.panasonic.com/cdbs/www-data/pdf/AOC0000/AOC0000C14.pdf"
			(at 0 0 270)
			(layer "F.Fab")
			(hide yes)
			(effects
				(font
					(size 1.27 1.27)
					(thickness 0.15)
				)
			)
		)
		(property "Description" "Zero Ohm Network Resistor, Jumper, 0201 [0603 Metric], Thick Film, Isolated, Flat, 4 Resistors"
			(at 0 0 270)
			(layer "F.Fab")
			(hide yes)
			(effects
				(font
					(size 1.27 1.27)
					(thickness 0.15)
				)
			)
		)
		(property "Author" "Antmicro"
			(at 74.975 317.475 0)
			(layer "F.Fab")
			(hide yes)
			(effects
				(font
					(size 1 1)
					(thickness 0.15)
				)
			)
		)
		(property "DNP" "DNP"
			(at 74.975 317.475 0)
			(layer "F.Fab")
			(hide yes)
			(effects
				(font
					(size 1 1)
					(thickness 0.15)
				)
			)
		)
		(property "License" "Apache-2.0"
			(at 74.975 317.475 0)
			(layer "F.Fab")
			(hide yes)
			(effects
				(font
					(size 1 1)
					(thickness 0.15)
				)
			)
		)
		(property "MPN" "EXB-18VR000X"
			(at 74.975 317.475 0)
			(layer "F.Fab")
			(hide yes)
			(effects
				(font
					(size 1 1)
					(thickness 0.15)
				)
			)
		)
		(property "Manufacturer" "Panasonic"
			(at 74.975 317.475 0)
			(layer "F.Fab")
			(hide yes)
			(effects
				(font
					(size 1 1)
					(thickness 0.15)
				)
			)
		)
		(property "Val" "4x0R_0201"
			(at 74.975 317.475 0)
			(layer "F.Fab")
			(hide yes)
			(effects
				(font
					(size 1 1)
					(thickness 0.15)
				)
			)
		)
		(sheetname "/FPGA MSSIO/")
		(sheetfile "fpga-mssio.kicad_sch")
		(attr smd dnp)
		(fp_line
			(start -0.8 -0.45)
			(end -0.8 0.45)
			(stroke
				(width 0.12)
				(type solid)
			)
			(layer "F.SilkS")
		)
		(fp_line
			(start 0.8 -0.45)
			(end 0.8 0.45)
			(stroke
				(width 0.12)
				(type solid)
			)
			(layer "F.SilkS")
		)
		(fp_rect
			(start -0.898 -0.66)
			(end 0.898 0.65)
			(stroke
				(width 0.05)
				(type solid)
			)
			(fill no)
			(layer "F.CrtYd")
		)
		(fp_text user "Author: Antmicro"
			(at -1.051 4.599 270)
			(layer "F.Fab")
			(effects
				(font
					(size 0.7 0.7)
					(thickness 0.15)
				)
				(justify left bottom)
			)
		)
		(fp_text user "License: Apache-2.0"
			(at -1.051 6 270)
			(layer "F.Fab")
			(effects
				(font
					(size 0.7 0.7)
					(thickness 0.15)
				)
				(justify left bottom)
			)
		)
		(fp_text user "${REFERENCE}"
			(at -1.051 3.2 270)
			(layer "F.Fab")
			(effects
				(font
					(size 0.7 0.7)
					(thickness 0.15)
				)
				(justify left bottom)
			)
		)
		(pad "1" smd roundrect
			(at -0.6 0.298 270)
			(size 0.2 0.4)
			(layers "F.Cu" "F.Mask" "F.Paste")
			(roundrect_rratio 0.25)
			(net 629 "unconnected-(R27-R1.1-Pad1)")
			(pinfunction "R1.1")
			(pintype "passive+no_connect")
		)
		(pad "2" smd roundrect
			(at -0.202 0.298 270)
			(size 0.2 0.4)
			(layers "F.Cu" "F.Mask" "F.Paste")
			(roundrect_rratio 0.25)
			(net 278 "/FPGA MSSIO/SD.CLK")
			(pinfunction "R2.1")
			(pintype "passive")
		)
		(pad "3" smd roundrect
			(at 0.2 0.298 270)
			(size 0.2 0.4)
			(layers "F.Cu" "F.Mask" "F.Paste")
			(roundrect_rratio 0.25)
			(net 388 "/FPGA MSSIO/SD.CMD")
			(pinfunction "R3.1")
			(pintype "passive")
		)
		(pad "4" smd roundrect
			(at 0.598 0.298 270)
			(size 0.2 0.4)
			(layers "F.Cu" "F.Mask" "F.Paste")
			(roundrect_rratio 0.25)
			(net 44 "SD_PWR_ON")
			(pinfunction "R4.1")
			(pintype "passive")
		)
		(pad "5" smd roundrect
			(at 0.598 -0.3 270)
			(size 0.2 0.4)
			(layers "F.Cu" "F.Mask" "F.Paste")
			(roundrect_rratio 0.25)
			(net 624 "/FPGA MSSIO/MEM.STRB")
			(pinfunction "R4.2")
			(pintype "passive")
		)
		(pad "6" smd roundrect
			(at 0.2 -0.3 270)
			(size 0.2 0.4)
			(layers "F.Cu" "F.Mask" "F.Paste")
			(roundrect_rratio 0.25)
			(net 625 "/FPGA MSSIO/MEM.CMD")
			(pinfunction "R3.2")
			(pintype "passive")
		)
		(pad "7" smd roundrect
			(at -0.202 -0.3 270)
			(size 0.2 0.4)
			(layers "F.Cu" "F.Mask" "F.Paste")
			(roundrect_rratio 0.25)
			(net 265 "/FPGA MSSIO/MEM.CLK")
			(pinfunction "R2.2")
			(pintype "passive")
		)
		(pad "8" smd roundrect
			(at -0.6 -0.3 270)
			(size 0.2 0.4)
			(layers "F.Cu" "F.Mask" "F.Paste")
			(roundrect_rratio 0.25)
			(net 628 "unconnected-(R27-R1.2-Pad8)")
			(pinfunction "R1.2")
			(pintype "passive+no_connect")
		)
	)
	(footprint "antmicro-footprints:TP_SMD_0.75mm"
		(layer "F.Cu")
		(at 228.47 147.815)
		(property "Reference" "TP9"
			(at 9.71 2.955 0)
			(layer "F.SilkS")
			(hide yes)
			(effects
				(font
					(size 0.7 0.7)
					(thickness 0.15)
				)
				(justify left bottom)
			)
		)
		(property "Value" "TP_0.75mm_SMD"
			(at 0 1.2 0)
			(layer "F.Fab")
			(hide yes)
			(effects
				(font
					(size 0.7 0.7)
					(thickness 0.15)
				)
				(justify left bottom)
			)
		)
		(property "Description" "SMT test point"
			(at 0 0 0)
			(layer "F.Fab")
			(hide yes)
			(effects
				(font
					(size 1.27 1.27)
					(thickness 0.15)
				)
			)
		)
		(property "Author" "Antmicro"
			(at 0 0 0)
			(layer "F.Fab")
			(hide yes)
			(effects
				(font
					(size 1 1)
					(thickness 0.15)
				)
			)
		)
		(property "License" "Apache-2.0"
			(at 0 0 0)
			(layer "F.Fab")
			(hide yes)
			(effects
				(font
					(size 1 1)
					(thickness 0.15)
				)
			)
		)
		(property "MPN" ""
			(at 0 0 0)
			(layer "F.Fab")
			(hide yes)
			(effects
				(font
					(size 1 1)
					(thickness 0.15)
				)
			)
		)
		(property "Manufacturer" ""
			(at 0 0 0)
			(layer "F.Fab")
			(hide yes)
			(effects
				(font
					(size 1 1)
					(thickness 0.15)
				)
			)
		)
		(property "Public" "False"
			(at 0 0 0)
			(layer "F.Fab")
			(hide yes)
			(effects
				(font
					(size 1 1)
					(thickness 0.15)
				)
			)
		)
		(sheetname "/WiFi_Bluetooth/")
		(sheetfile "wifi_bt.kicad_sch")
		(attr exclude_from_pos_files exclude_from_bom)
		(fp_circle
			(center 0 0)
			(end 0.475 0)
			(stroke
				(width 0.05)
				(type default)
			)
			(fill no)
			(layer "F.CrtYd")
		)
		(fp_text user "License: Apache-2.0"
			(at -0.4 5.101 0)
			(layer "F.Fab")
			(effects
				(font
					(size 0.7 0.7)
					(thickness 0.15)
				)
				(justify left bottom)
			)
		)
		(fp_text user "${REFERENCE}"
			(at -0.4 2.7 0)
			(layer "F.Fab")
			(effects
				(font
					(size 0.7 0.7)
					(thickness 0.15)
				)
				(justify left bottom)
			)
		)
		(fp_text user "Author: Antmicro"
			(at -0.4 3.901 0)
			(layer "F.Fab")
			(effects
				(font
					(size 0.7 0.7)
					(thickness 0.15)
				)
				(justify left bottom)
			)
		)
		(pad "1" smd circle
			(at 0 0)
			(size 0.75 0.75)
			(layers "F.Cu" "F.Mask")
			(net 506 "Net-(U26A-BT_UART_RTS_N)")
			(pinfunction "1")
			(pintype "passive")
		)
	)
	(footprint "antmicro-footprints:SOT-523"
		(layer "F.Cu")
		(at 190.52 119.9)
		(property "Reference" "Q2"
			(at -1.31 -0.98 0)
			(layer "F.SilkS")
			(effects
				(font
					(size 0.7 0.7)
					(thickness 0.15)
				)
				(justify left bottom)
			)
		)
		(property "Value" "DMG1012T-7"
			(at 0.1 1.824 0)
			(layer "F.Fab")
			(hide yes)
			(effects
				(font
					(size 0.7 0.7)
					(thickness 0.15)
				)
				(justify left bottom)
			)
		)
		(property "Datasheet" "https://www.diodes.com/assets/Datasheets/ds31783.pdf"
			(at 0 0 0)
			(layer "F.Fab")
			(hide yes)
			(effects
				(font
					(size 1.27 1.27)
					(thickness 0.15)
				)
			)
		)
		(property "Description" "Power MOSFET, N Channel, 20 V, 630 mA, 0.3 ohm, SOT-523, Surface Mount"
			(at 0 0 0)
			(layer "F.Fab")
			(hide yes)
			(effects
				(font
					(size 1.27 1.27)
					(thickness 0.15)
				)
			)
		)
		(property "Author" "Antmicro"
			(at 0 0 0)
			(layer "F.Fab")
			(hide yes)
			(effects
				(font
					(size 1 1)
					(thickness 0.15)
				)
			)
		)
		(property "License" "Apache-2.0"
			(at 0 0 0)
			(layer "F.Fab")
			(hide yes)
			(effects
				(font
					(size 1 1)
					(thickness 0.15)
				)
			)
		)
		(property "MPN" "DMG1012T-7"
			(at 0 0 0)
			(layer "F.Fab")
			(hide yes)
			(effects
				(font
					(size 1 1)
					(thickness 0.15)
				)
			)
		)
		(property "Manufacturer" "Diodes Incorporated"
			(at 0 0 0)
			(layer "F.Fab")
			(hide yes)
			(effects
				(font
					(size 1 1)
					(thickness 0.15)
				)
			)
		)
		(property "Public" ""
			(at 0 0 0)
			(layer "F.Fab")
			(hide yes)
			(effects
				(font
					(size 1 1)
					(thickness 0.15)
				)
			)
		)
		(sheetname "/Top Connector/")
		(sheetfile "top-connector.kicad_sch")
		(attr smd)
		(fp_line
			(start -0.927 -0.351)
			(end -0.725 -0.551)
			(stroke
				(width 0.15)
				(type solid)
			)
			(layer "F.SilkS")
		)
		(fp_line
			(start -0.927 -0.051)
			(end -0.927 -0.351)
			(stroke
				(width 0.15)
				(type solid)
			)
			(layer "F.SilkS")
		)
		(fp_line
			(start -0.725 -0.551)
			(end -0.277 -0.551)
			(stroke
				(width 0.15)
				(type solid)
			)
			(layer "F.SilkS")
		)
		(fp_line
			(start -0.277 -0.551)
			(end -0.277 -0.75)
			(stroke
				(width 0.15)
				(type solid)
			)
			(layer "F.SilkS")
		)
		(fp_circle
			(center -0.9652 0.9652)
			(end -0.9152 0.9652)
			(stroke
				(width 0.15)
				(type solid)
			)
			(fill yes)
			(layer "F.SilkS")
		)
		(fp_line
			(start -1.12 -1.16)
			(end -1.12 1.15)
			(stroke
				(width 0.05)
				(type solid)
			)
			(layer "F.CrtYd")
		)
		(fp_line
			(start -1.12 -1.16)
			(end 1.1 -1.16)
			(stroke
				(width 0.05)
				(type solid)
			)
			(layer "F.CrtYd")
		)
		(fp_line
			(start -1.12 1.15)
			(end 1.1 1.15)
			(stroke
				(width 0.05)
				(type solid)
			)
			(layer "F.CrtYd")
		)
		(fp_line
			(start 1.1 -1.16)
			(end 1.1 1.15)
			(stroke
				(width 0.05)
				(type solid)
			)
			(layer "F.CrtYd")
		)
		(fp_line
			(start -0.802 -0.276)
			(end -0.802 0.424)
			(stroke
				(width 0.15)
				(type solid)
			)
			(layer "F.Fab")
		)
		(fp_line
			(start -0.652 -0.425)
			(end -0.802 -0.276)
			(stroke
				(width 0.15)
				(type solid)
			)
			(layer "F.Fab")
		)
		(fp_line
			(start 0.8 -0.425)
			(end -0.652 -0.425)
			(stroke
				(width 0.15)
				(type solid)
			)
			(layer "F.Fab")
		)
		(fp_line
			(start 0.8 -0.425)
			(end 0.8 0.424)
			(stroke
				(width 0.15)
				(type solid)
			)
			(layer "F.Fab")
		)
		(fp_line
			(start 0.8 0.424)
			(end -0.802 0.424)
			(stroke
				(width 0.15)
				(type solid)
			)
			(layer "F.Fab")
		)
		(fp_circle
			(center -0.9652 0.9652)
			(end -0.9144 0.9652)
			(stroke
				(width 0.15)
				(type solid)
			)
			(fill no)
			(layer "F.Fab")
		)
		(fp_text user "License: Apache-2.0"
			(at -1.12 5.024 0)
			(layer "F.Fab")
			(effects
				(font
					(size 0.7 0.7)
					(thickness 0.15)
				)
				(justify left bottom)
			)
		)
		(fp_text user "Author: Antmicro"
			(at -1.12 6.224 0)
			(layer "F.Fab")
			(effects
				(font
					(size 0.7 0.7)
					(thickness 0.15)
				)
				(justify left bottom)
			)
		)
		(fp_text user "${REFERENCE}"
			(at -1.12 3.824 0)
			(layer "F.Fab")
			(effects
				(font
					(size 0.7 0.7)
					(thickness 0.15)
				)
				(justify left bottom)
			)
		)
		(pad "1" smd rect
			(at -0.5 0.65)
			(size 0.4 0.51)
			(layers "F.Cu" "F.Mask" "F.Paste")
			(net 649 "VDD")
			(pinfunction "G")
			(pintype "input")
		)
		(pad "2" smd rect
			(at 0.498 0.65)
			(size 0.4 0.51)
			(layers "F.Cu" "F.Mask" "F.Paste")
			(net 417 "GND")
			(pinfunction "S")
			(pintype "passive")
		)
		(pad "3" smd rect
			(at 0 -0.652)
			(size 0.4 0.51)
			(layers "F.Cu" "F.Mask" "F.Paste")
			(net 98 "/Top Connector/PI_LED_nPWR")
			(pinfunction "D")
			(pintype "passive")
		)
	)
	(footprint "antmicro-footprints:R_0402_1005Metric"
		(layer "F.Cu")
		(at 210.425 122.3406 180)
		(descr "Resistor SMD 0402")
		(tags "resistor SMD 0402")
		(property "Reference" "R87"
			(at -1.215 -2.3594 0)
			(layer "F.SilkS")
			(effects
				(font
					(size 0.7 0.7)
					(thickness 0.15)
				)
				(justify right bottom)
			)
		)
		(property "Value" "R_0R_0402"
			(at -1.011843 1.772047 0)
			(layer "F.Fab")
			(hide yes)
			(effects
				(font
					(size 0.7 0.7)
					(thickness 0.15)
				)
				(justify right bottom)
			)
		)
		(property "Datasheet" "https://industrial.panasonic.com/cdbs/www-data/pdf/RDA0000/AOA0000C301.pdf"
			(at 0 0 180)
			(layer "F.Fab")
			(hide yes)
			(effects
				(font
					(size 1.27 1.27)
					(thickness 0.15)
				)
			)
		)
		(property "Description" "SMD Chip Resistor, Jumper, 0 ohm, 100 mW, 0402 [1005 Metric], Thick Film, General Purpose"
			(at 0 0 180)
			(layer "F.Fab")
			(hide yes)
			(effects
				(font
					(size 1.27 1.27)
					(thickness 0.15)
				)
			)
		)
		(property "Author" "Antmicro"
			(at 420.85 244.6812 0)
			(layer "F.Fab")
			(hide yes)
			(effects
				(font
					(size 1 1)
					(thickness 0.15)
				)
			)
		)
		(property "Current" "1A"
			(at 420.85 244.6812 0)
			(layer "F.Fab")
			(hide yes)
			(effects
				(font
					(size 1 1)
					(thickness 0.15)
				)
			)
		)
		(property "License" "Apache-2.0"
			(at 420.85 244.6812 0)
			(layer "F.Fab")
			(hide yes)
			(effects
				(font
					(size 1 1)
					(thickness 0.15)
				)
			)
		)
		(property "MPN" "ERJ2GE0R00X"
			(at 420.85 244.6812 0)
			(layer "F.Fab")
			(hide yes)
			(effects
				(font
					(size 1 1)
					(thickness 0.15)
				)
			)
		)
		(property "Manufacturer" "Panasonic"
			(at 420.85 244.6812 0)
			(layer "F.Fab")
			(hide yes)
			(effects
				(font
					(size 1 1)
					(thickness 0.15)
				)
			)
		)
		(property "Public" ""
			(at 420.85 244.6812 0)
			(layer "F.Fab")
			(hide yes)
			(effects
				(font
					(size 1 1)
					(thickness 0.15)
				)
			)
		)
		(property "Tolerance" "~"
			(at 420.85 244.6812 0)
			(layer "F.Fab")
			(hide yes)
			(effects
				(font
					(size 1 1)
					(thickness 0.15)
				)
			)
		)
		(property "Val" "0R"
			(at 420.85 244.6812 0)
			(layer "F.Fab")
			(hide yes)
			(effects
				(font
					(size 1 1)
					(thickness 0.15)
				)
			)
		)
		(sheetname "/FPGA MSS/")
		(sheetfile "fpga-mss.kicad_sch")
		(attr smd)
		(fp_rect
			(start -0.925 -0.47)
			(end 0.925 0.47)
			(stroke
				(width 0.05)
				(type default)
			)
			(fill no)
			(layer "F.CrtYd")
		)
		(fp_rect
			(start -0.5 -0.25)
			(end 0.5 0.25)
			(stroke
				(width 0.15)
				(type solid)
			)
			(fill no)
			(layer "F.Fab")
		)
		(fp_text user "Author: Antmicro"
			(at -0.95 4.169 180)
			(layer "F.Fab")
			(effects
				(font
					(size 0.7 0.7)
					(thickness 0.15)
				)
				(justify left bottom)
			)
		)
		(fp_text user "License: Apache-2.0"
			(at -0.95 5.169 180)
			(layer "F.Fab")
			(effects
				(font
					(size 0.7 0.7)
					(thickness 0.15)
				)
				(justify left bottom)
			)
		)
		(fp_text user "${REFERENCE}"
			(at -0.95 3.168 180)
			(layer "F.Fab")
			(effects
				(font
					(size 0.7 0.7)
					(thickness 0.15)
				)
				(justify left bottom)
			)
		)
		(pad "1" smd roundrect
			(at -0.48 0 180)
			(size 0.59 0.64)
			(layers "F.Cu" "F.Mask" "F.Paste")
			(roundrect_rratio 0.25)
			(net 302 "/FPGA MSS/MSS_CLK_N")
			(pintype "passive")
		)
		(pad "2" smd roundrect
			(at 0.48 0 180)
			(size 0.59 0.64)
			(layers "F.Cu" "F.Mask" "F.Paste")
			(roundrect_rratio 0.25)
			(net 9 "MSS_REFCLK_N")
			(pintype "passive")
		)
	)
)
